(kicad_pcb
	(version 20260206)
	(generator "pcbnew")
	(generator_version "10.0")
	(general
		(thickness 1.6)
		(legacy_teardrops no)
	)
	(paper "A4")
	(title_block
		(title "panther-plus-userver — 13130-1b_20150205.brd")
		(comment 1 "Honey Badger (Wiwynn) / footprints 341-349 of 1509")
	)
	(layers
		(0 "F.Cu" signal "TOP")
		(4 "In1.Cu" signal "L2")
		(6 "In2.Cu" signal "L3")
		(8 "In3.Cu" signal "L4")
		(10 "In4.Cu" signal "L5")
		(12 "In5.Cu" signal "L6")
		(14 "In6.Cu" signal "L7")
		(16 "In7.Cu" signal "L8")
		(18 "In8.Cu" signal "L9")
		(20 "In9.Cu" signal "L10")
		(22 "In10.Cu" signal "L11")
		(2 "B.Cu" signal "BOTTOM")
		(9 "F.Adhes" user "F.Adhesive")
		(11 "B.Adhes" user "B.Adhesive")
		(13 "F.Paste" user "Package Geometry/Pastemask Top")
		(15 "B.Paste" user "Package Geometry/Pastemask Bottom")
		(5 "F.SilkS" user "Ref Des/Silkscreen Top")
		(7 "B.SilkS" user "Ref Des/Silkscreen Bottom")
		(1 "F.Mask" user "Board Geometry/Soldermask Top")
		(3 "B.Mask" user "Board Geometry/Soldermask Bottom")
		(17 "Dwgs.User" user "User.Drawings")
		(19 "Cmts.User" user "User.Comments")
		(21 "Eco1.User" user "User.Eco1")
		(23 "Eco2.User" user "User.Eco2")
		(25 "Edge.Cuts" user "Board Geometry/Outline")
		(27 "Margin" user)
		(31 "F.CrtYd" user "Package Geometry/Place Bound Top")
		(29 "B.CrtYd" user "Package Geometry/Place Bound Bottom")
		(35 "F.Fab" user "Ref Des/Assembly Top")
		(33 "B.Fab" user "Ref Des/Assembly Bottom")
	)
	(footprint ""
		(layer "F.Cu")
		(at 182.753 -34.798 -90)
		(property "Reference" "PR138"
			(at 0 0 270)
			(layer "F.SilkS")
			(hide yes)
			(effects
				(font
					(size 1.27 1.27)
				)
			)
		)
		(property "Value" "10KR2F-2-GP"
			(at 1.7907 -1.1176 270)
			(unlocked yes)
			(layer "F.Fab")
			(hide yes)
			(effects
				(font
					(size 1.016 1.016)
					(thickness 0.1524)
				)
			)
		)
		(property "Device Type" "R402H16"
			(at 1.7907 -2.6416 270)
			(unlocked yes)
			(layer "F.Fab")
			(hide yes)
			(effects
				(font
					(size 1.016 1.016)
					(thickness 0.1524)
				)
			)
		)
		(duplicate_pad_numbers_are_jumpers no)
		(fp_rect
			(start -0.381 0.8382)
			(end 0.381 -0.8382)
			(stroke
				(width 0)
				(type default)
			)
			(fill no)
			(layer "F.CrtYd")
		)
		(fp_rect
			(start -0.381 0.8382)
			(end 0.381 -0.8382)
			(stroke
				(width 0)
				(type default)
			)
			(fill no)
			(layer "F.Fab")
		)
		(pad "1" smd custom
			(at 0 -0.4318 270)
			(size 0.127 0.127)
			(layers "F.Cu" "F.Mask" "F.Paste")
			(net "PWRGD_PVDDR_PG")
			(options
				(clearance outline)
				(anchor circle)
			)
			(primitives
				(gr_poly
					(pts
						(arc
							(start -0.2032 -0.2794)
							(mid -0.239121 -0.264521)
							(end -0.254 -0.2286)
						)
						(arc
							(start -0.254 0.2286)
							(mid -0.239121 0.264521)
							(end -0.2032 0.2794)
						)
						(arc
							(start 0.2032 0.2794)
							(mid 0.239121 0.264521)
							(end 0.254 0.2286)
						)
						(arc
							(start 0.254 -0.2286)
							(mid 0.239121 -0.264521)
							(end 0.2032 -0.2794)
						)
					)
					(width 0)
					(fill yes)
				)
			)
		)
		(pad "2" smd custom
			(at 0 0.4318 270)
			(size 0.127 0.127)
			(layers "F.Cu" "F.Mask" "F.Paste")
			(net "P3V3_STBY")
			(options
				(clearance outline)
				(anchor circle)
			)
			(primitives
				(gr_poly
					(pts
						(arc
							(start -0.2032 -0.2794)
							(mid -0.239121 -0.264521)
							(end -0.254 -0.2286)
						)
						(arc
							(start -0.254 0.2286)
							(mid -0.239121 0.264521)
							(end -0.2032 0.2794)
						)
						(arc
							(start 0.2032 0.2794)
							(mid 0.239121 0.264521)
							(end 0.254 0.2286)
						)
						(arc
							(start 0.254 -0.2286)
							(mid 0.239121 -0.264521)
							(end 0.2032 -0.2794)
						)
					)
					(width 0)
					(fill yes)
				)
			)
		)
	)
	(footprint ""
		(layer "F.Cu")
		(at 135.509 -18.796)
		(property "Reference" "R52"
			(at 0 0 0)
			(layer "F.SilkS")
			(hide yes)
			(effects
				(font
					(size 1.27 1.27)
				)
			)
		)
		(property "Value" "0R2J-2-GP"
			(at 0.064008 -3.993896 0)
			(unlocked yes)
			(layer "F.Fab")
			(hide yes)
			(effects
				(font
					(size 1.016 1.016)
					(thickness 0.1524)
				)
			)
		)
		(property "Device Type" "R402H16"
			(at 0.064008 -5.517896 0)
			(unlocked yes)
			(layer "F.Fab")
			(hide yes)
			(effects
				(font
					(size 1.016 1.016)
					(thickness 0.1524)
				)
			)
		)
		(duplicate_pad_numbers_are_jumpers no)
		(fp_rect
			(start -0.381 0.8382)
			(end 0.381 -0.8382)
			(stroke
				(width 0)
				(type default)
			)
			(fill no)
			(layer "F.CrtYd")
		)
		(fp_rect
			(start -0.381 0.8382)
			(end 0.381 -0.8382)
			(stroke
				(width 0)
				(type default)
			)
			(fill no)
			(layer "F.Fab")
		)
		(pad "1" smd custom
			(at 0 -0.4318)
			(size 0.127 0.127)
			(layers "F.Cu" "F.Mask" "F.Paste")
			(net "POWER_CONTROL")
			(options
				(clearance outline)
				(anchor circle)
			)
			(primitives
				(gr_poly
					(pts
						(arc
							(start -0.2032 -0.2794)
							(mid -0.239121 -0.264521)
							(end -0.254 -0.2286)
						)
						(arc
							(start -0.254 0.2286)
							(mid -0.239121 0.264521)
							(end -0.2032 0.2794)
						)
						(arc
							(start 0.2032 0.2794)
							(mid 0.239121 0.264521)
							(end 0.254 0.2286)
						)
						(arc
							(start 0.254 -0.2286)
							(mid 0.239121 -0.264521)
							(end 0.2032 -0.2794)
						)
					)
					(width 0)
					(fill yes)
				)
			)
		)
		(pad "2" smd custom
			(at 0 0.4318)
			(size 0.127 0.127)
			(layers "F.Cu" "F.Mask" "F.Paste")
			(net "FPGA_PWRBTN#")
			(options
				(clearance outline)
				(anchor circle)
			)
			(primitives
				(gr_poly
					(pts
						(arc
							(start -0.2032 -0.2794)
							(mid -0.239121 -0.264521)
							(end -0.254 -0.2286)
						)
						(arc
							(start -0.254 0.2286)
							(mid -0.239121 0.264521)
							(end -0.2032 0.2794)
						)
						(arc
							(start 0.2032 0.2794)
							(mid 0.239121 0.264521)
							(end 0.254 0.2286)
						)
						(arc
							(start 0.254 -0.2286)
							(mid 0.239121 -0.264521)
							(end 0.2032 -0.2794)
						)
					)
					(width 0)
					(fill yes)
				)
			)
		)
	)
	(footprint ""
		(layer "F.Cu")
		(at 73.66 -27.178 -90)
		(property "Reference" "R352"
			(at 0 0 270)
			(layer "F.SilkS")
			(hide yes)
			(effects
				(font
					(size 1.27 1.27)
				)
			)
		)
		(property "Value" "0R2J-2-GP"
			(at 0.064008 -3.993896 270)
			(unlocked yes)
			(layer "F.Fab")
			(hide yes)
			(effects
				(font
					(size 1.016 1.016)
					(thickness 0.1524)
				)
			)
		)
		(property "Device Type" "R402H16"
			(at 0.064008 -5.517896 270)
			(unlocked yes)
			(layer "F.Fab")
			(hide yes)
			(effects
				(font
					(size 1.016 1.016)
					(thickness 0.1524)
				)
			)
		)
		(duplicate_pad_numbers_are_jumpers no)
		(fp_rect
			(start -0.381 0.8382)
			(end 0.381 -0.8382)
			(stroke
				(width 0)
				(type default)
			)
			(fill no)
			(layer "F.CrtYd")
		)
		(fp_rect
			(start -0.381 0.8382)
			(end 0.381 -0.8382)
			(stroke
				(width 0)
				(type default)
			)
			(fill no)
			(layer "F.Fab")
		)
		(pad "1" smd custom
			(at 0 -0.4318 270)
			(size 0.127 0.127)
			(layers "F.Cu" "F.Mask" "F.Paste")
			(net "CPU_RSMRST_R#")
			(options
				(clearance outline)
				(anchor circle)
			)
			(primitives
				(gr_poly
					(pts
						(arc
							(start -0.2032 -0.2794)
							(mid -0.239121 -0.264521)
							(end -0.254 -0.2286)
						)
						(arc
							(start -0.254 0.2286)
							(mid -0.239121 0.264521)
							(end -0.2032 0.2794)
						)
						(arc
							(start 0.2032 0.2794)
							(mid 0.239121 0.264521)
							(end 0.254 0.2286)
						)
						(arc
							(start 0.254 -0.2286)
							(mid 0.239121 -0.264521)
							(end 0.2032 -0.2794)
						)
					)
					(width 0)
					(fill yes)
				)
			)
		)
		(pad "2" smd custom
			(at 0 0.4318 270)
			(size 0.127 0.127)
			(layers "F.Cu" "F.Mask" "F.Paste")
			(net "CPU_RSMRST#")
			(options
				(clearance outline)
				(anchor circle)
			)
			(primitives
				(gr_poly
					(pts
						(arc
							(start -0.2032 -0.2794)
							(mid -0.239121 -0.264521)
							(end -0.254 -0.2286)
						)
						(arc
							(start -0.254 0.2286)
							(mid -0.239121 0.264521)
							(end -0.2032 0.2794)
						)
						(arc
							(start 0.2032 0.2794)
							(mid 0.239121 0.264521)
							(end 0.254 0.2286)
						)
						(arc
							(start 0.254 -0.2286)
							(mid 0.239121 -0.264521)
							(end 0.2032 -0.2794)
						)
					)
					(width 0)
					(fill yes)
				)
			)
		)
	)
	(footprint ""
		(layer "F.Cu")
		(at 19.5834 -67.1576 180)
		(property "Reference" "PC17"
			(at 0 0 180)
			(layer "F.SilkS")
			(hide yes)
			(effects
				(font
					(size 1.27 1.27)
				)
			)
		)
		(property "Value" "SCD022U16V2KX-3GP"
			(at 1.8923 -1.2065 180)
			(unlocked yes)
			(layer "F.Fab")
			(hide yes)
			(effects
				(font
					(size 1.016 1.016)
					(thickness 0.1524)
				)
			)
		)
		(property "Device Type" "C402H22"
			(at 1.8923 -2.7305 180)
			(unlocked yes)
			(layer "F.Fab")
			(hide yes)
			(effects
				(font
					(size 1.016 1.016)
					(thickness 0.1524)
				)
			)
		)
		(duplicate_pad_numbers_are_jumpers no)
		(fp_rect
			(start -0.381 0.7366)
			(end 0.381 -0.7366)
			(stroke
				(width 0)
				(type default)
			)
			(fill no)
			(layer "F.CrtYd")
		)
		(fp_rect
			(start -0.381 0.7366)
			(end 0.381 -0.7366)
			(stroke
				(width 0)
				(type default)
			)
			(fill no)
			(layer "F.Fab")
		)
		(pad "1" smd custom
			(at 0 -0.4572 180)
			(size 0.1143 0.1143)
			(layers "F.Cu" "F.Mask" "F.Paste")
			(net "VR_PVNN_ISUMN")
			(options
				(clearance outline)
				(anchor circle)
			)
			(primitives
				(gr_poly
					(pts
						(arc
							(start -0.254 -0.1778)
							(mid -0.239121 -0.213721)
							(end -0.2032 -0.2286)
						)
						(arc
							(start 0.2032 -0.2286)
							(mid 0.239121 -0.213721)
							(end 0.254 -0.1778)
						)
						(arc
							(start 0.254 0.1778)
							(mid 0.239121 0.213721)
							(end 0.2032 0.2286)
						)
						(arc
							(start -0.2032 0.2286)
							(mid -0.239121 0.213721)
							(end -0.254 0.1778)
						)
					)
					(width 0)
					(fill yes)
				)
			)
		)
		(pad "2" smd custom
			(at 0 0.4572 180)
			(size 0.1143 0.1143)
			(layers "F.Cu" "F.Mask" "F.Paste")
			(net "VR_PVNN_ISUMP")
			(options
				(clearance outline)
				(anchor circle)
			)
			(primitives
				(gr_poly
					(pts
						(arc
							(start -0.254 -0.1778)
							(mid -0.239121 -0.213721)
							(end -0.2032 -0.2286)
						)
						(arc
							(start 0.2032 -0.2286)
							(mid 0.239121 -0.213721)
							(end 0.254 -0.1778)
						)
						(arc
							(start 0.254 0.1778)
							(mid 0.239121 0.213721)
							(end 0.2032 0.2286)
						)
						(arc
							(start -0.2032 0.2286)
							(mid -0.239121 0.213721)
							(end -0.254 0.1778)
						)
					)
					(width 0)
					(fill yes)
				)
			)
		)
	)
	(footprint ""
		(layer "F.Cu")
		(at 53.721 -68.072 180)
		(property "Reference" "PC31"
			(at 0 0 180)
			(layer "F.SilkS")
			(hide yes)
			(effects
				(font
					(size 1.27 1.27)
				)
			)
		)
		(property "Value" "SC47U6D3V5MX-1-GP"
			(at 0 -4.9022 180)
			(unlocked yes)
			(layer "F.Fab")
			(hide yes)
			(effects
				(font
					(size 1.016 1.016)
					(thickness 0.1524)
				)
			)
		)
		(property "Device Type" "C805H54"
			(at 0 -6.8072 180)
			(unlocked yes)
			(layer "F.Fab")
			(hide yes)
			(effects
				(font
					(size 1.016 1.016)
					(thickness 0.1524)
				)
			)
		)
		(duplicate_pad_numbers_are_jumpers no)
		(fp_line
			(start 0.6096 0)
			(end -0.6096 0)
			(stroke
				(width 0.3048)
				(type default)
			)
			(layer "F.SilkS")
		)
		(fp_poly
			(pts
				(xy -0.9017 1.4351) (xy 0.9017 1.4351) (xy 0.9017 -1.4351) (xy -0.9017 -1.4351)
			)
			(stroke
				(width 0)
				(type default)
			)
			(fill no)
			(layer "F.CrtYd")
		)
		(fp_poly
			(pts
				(xy 0.9017 1.4351) (xy 0.9017 -1.4351) (xy -0.9017 -1.4351) (xy -0.9017 1.4351)
			)
			(stroke
				(width 0)
				(type default)
			)
			(fill no)
			(layer "F.Fab")
		)
		(pad "1" smd rect
			(at 0 -0.8382 180)
			(size 1.5494 0.9398)
			(layers "F.Cu" "F.Mask" "F.Paste")
			(net "PVNN")
		)
		(pad "2" smd rect
			(at 0 0.8382 180)
			(size 1.5494 0.9398)
			(layers "F.Cu" "F.Mask" "F.Paste")
			(net "GND")
		)
	)
	(footprint ""
		(layer "F.Cu")
		(at 161.925 -59.309)
		(property "Reference" "C367"
			(at 0 0 0)
			(layer "F.SilkS")
			(hide yes)
			(effects
				(font
					(size 1.27 1.27)
				)
			)
		)
		(property "Value" "SC47U6D3V5MX-1-GP"
			(at 0 -4.9022 0)
			(unlocked yes)
			(layer "F.Fab")
			(hide yes)
			(effects
				(font
					(size 1.016 1.016)
					(thickness 0.1524)
				)
			)
		)
		(property "Device Type" "C805H54"
			(at 0 -6.8072 0)
			(unlocked yes)
			(layer "F.Fab")
			(hide yes)
			(effects
				(font
					(size 1.016 1.016)
					(thickness 0.1524)
				)
			)
		)
		(duplicate_pad_numbers_are_jumpers no)
		(fp_line
			(start 0.6096 0)
			(end -0.6096 0)
			(stroke
				(width 0.3048)
				(type default)
			)
			(layer "F.SilkS")
		)
		(fp_poly
			(pts
				(xy -0.9017 1.4351) (xy 0.9017 1.4351) (xy 0.9017 -1.4351) (xy -0.9017 -1.4351)
			)
			(stroke
				(width 0)
				(type default)
			)
			(fill no)
			(layer "F.CrtYd")
		)
		(fp_poly
			(pts
				(xy 0.9017 1.4351) (xy 0.9017 -1.4351) (xy -0.9017 -1.4351) (xy -0.9017 1.4351)
			)
			(stroke
				(width 0)
				(type default)
			)
			(fill no)
			(layer "F.Fab")
		)
		(pad "1" smd rect
			(at 0 -0.8382)
			(size 1.5494 0.9398)
			(layers "F.Cu" "F.Mask" "F.Paste")
			(net "PV_VDDR")
		)
		(pad "2" smd rect
			(at 0 0.8382)
			(size 1.5494 0.9398)
			(layers "F.Cu" "F.Mask" "F.Paste")
			(net "GND")
		)
	)
	(footprint ""
		(layer "F.Cu")
		(at 15.8496 -60.6552 -90)
		(property "Reference" "PR40"
			(at 0 0 270)
			(layer "F.SilkS")
			(hide yes)
			(effects
				(font
					(size 1.27 1.27)
				)
			)
		)
		(property "Value" "10D7R2F-GP"
			(at 1.7907 -1.1176 270)
			(unlocked yes)
			(layer "F.Fab")
			(hide yes)
			(effects
				(font
					(size 1.016 1.016)
					(thickness 0.1524)
				)
			)
		)
		(property "Device Type" "R402H16"
			(at 1.7907 -2.6416 270)
			(unlocked yes)
			(layer "F.Fab")
			(hide yes)
			(effects
				(font
					(size 1.016 1.016)
					(thickness 0.1524)
				)
			)
		)
		(duplicate_pad_numbers_are_jumpers no)
		(fp_rect
			(start -0.381 0.8382)
			(end 0.381 -0.8382)
			(stroke
				(width 0)
				(type default)
			)
			(fill no)
			(layer "F.CrtYd")
		)
		(fp_rect
			(start -0.381 0.8382)
			(end 0.381 -0.8382)
			(stroke
				(width 0)
				(type default)
			)
			(fill no)
			(layer "F.Fab")
		)
		(pad "1" smd custom
			(at 0 -0.4318 270)
			(size 0.127 0.127)
			(layers "F.Cu" "F.Mask" "F.Paste")
			(net "VR_95831_SDA")
			(options
				(clearance outline)
				(anchor circle)
			)
			(primitives
				(gr_poly
					(pts
						(arc
							(start -0.2032 -0.2794)
							(mid -0.239121 -0.264521)
							(end -0.254 -0.2286)
						)
						(arc
							(start -0.254 0.2286)
							(mid -0.239121 0.264521)
							(end -0.2032 0.2794)
						)
						(arc
							(start 0.2032 0.2794)
							(mid 0.239121 0.264521)
							(end 0.254 0.2286)
						)
						(arc
							(start 0.254 -0.2286)
							(mid 0.239121 -0.264521)
							(end 0.2032 -0.2794)
						)
					)
					(width 0)
					(fill yes)
				)
			)
		)
		(pad "2" smd custom
			(at 0 0.4318 270)
			(size 0.127 0.127)
			(layers "F.Cu" "F.Mask" "F.Paste")
			(net "SVID_CPU_DATA")
			(options
				(clearance outline)
				(anchor circle)
			)
			(primitives
				(gr_poly
					(pts
						(arc
							(start -0.2032 -0.2794)
							(mid -0.239121 -0.264521)
							(end -0.254 -0.2286)
						)
						(arc
							(start -0.254 0.2286)
							(mid -0.239121 0.264521)
							(end -0.2032 0.2794)
						)
						(arc
							(start 0.2032 0.2794)
							(mid 0.239121 0.264521)
							(end 0.254 0.2286)
						)
						(arc
							(start 0.254 -0.2286)
							(mid 0.239121 -0.264521)
							(end 0.2032 -0.2794)
						)
					)
					(width 0)
					(fill yes)
				)
			)
		)
	)
	(footprint ""
		(layer "F.Cu")
		(at 28.067 -58.0136 -90)
		(property "Reference" "PR44"
			(at 0 0 270)
			(layer "F.SilkS")
			(hide yes)
			(effects
				(font
					(size 1.27 1.27)
				)
			)
		)
		(property "Value" "0R2J-2-GP"
			(at 1.7907 -1.1176 270)
			(unlocked yes)
			(layer "F.Fab")
			(hide yes)
			(effects
				(font
					(size 1.016 1.016)
					(thickness 0.1524)
				)
			)
		)
		(property "Device Type" "R402H16"
			(at 1.7907 -2.6416 270)
			(unlocked yes)
			(layer "F.Fab")
			(hide yes)
			(effects
				(font
					(size 1.016 1.016)
					(thickness 0.1524)
				)
			)
		)
		(duplicate_pad_numbers_are_jumpers no)
		(fp_rect
			(start -0.381 0.8382)
			(end 0.381 -0.8382)
			(stroke
				(width 0)
				(type default)
			)
			(fill no)
			(layer "F.CrtYd")
		)
		(fp_rect
			(start -0.381 0.8382)
			(end 0.381 -0.8382)
			(stroke
				(width 0)
				(type default)
			)
			(fill no)
			(layer "F.Fab")
		)
		(pad "1" smd custom
			(at 0 -0.4318 270)
			(size 0.127 0.127)
			(layers "F.Cu" "F.Mask" "F.Paste")
			(net "VR_PVCCP_PVNN_VDD")
			(options
				(clearance outline)
				(anchor circle)
			)
			(primitives
				(gr_poly
					(pts
						(arc
							(start -0.2032 -0.2794)
							(mid -0.239121 -0.264521)
							(end -0.254 -0.2286)
						)
						(arc
							(start -0.254 0.2286)
							(mid -0.239121 0.264521)
							(end -0.2032 0.2794)
						)
						(arc
							(start 0.2032 0.2794)
							(mid 0.239121 0.264521)
							(end 0.254 0.2286)
						)
						(arc
							(start 0.254 -0.2286)
							(mid 0.239121 -0.264521)
							(end 0.2032 -0.2794)
						)
					)
					(width 0)
					(fill yes)
				)
			)
		)
		(pad "2" smd custom
			(at 0 0.4318 270)
			(size 0.127 0.127)
			(layers "F.Cu" "F.Mask" "F.Paste")
			(net "VR_PVCCP_PWM3")
			(options
				(clearance outline)
				(anchor circle)
			)
			(primitives
				(gr_poly
					(pts
						(arc
							(start -0.2032 -0.2794)
							(mid -0.239121 -0.264521)
							(end -0.254 -0.2286)
						)
						(arc
							(start -0.254 0.2286)
							(mid -0.239121 0.264521)
							(end -0.2032 0.2794)
						)
						(arc
							(start 0.2032 0.2794)
							(mid 0.239121 0.264521)
							(end 0.254 0.2286)
						)
						(arc
							(start 0.254 -0.2286)
							(mid 0.239121 -0.264521)
							(end 0.2032 -0.2794)
						)
					)
					(width 0)
					(fill yes)
				)
			)
		)
	)
	(footprint ""
		(layer "F.Cu")
		(at 117.475 -64.389 180)
		(property "Reference" "R225"
			(at 0 0 180)
			(layer "F.SilkS")
			(hide yes)
			(effects
				(font
					(size 1.27 1.27)
				)
			)
		)
		(property "Value" "0R2J-2-GP"
			(at 0.064008 -3.993896 180)
			(unlocked yes)
			(layer "F.Fab")
			(hide yes)
			(effects
				(font
					(size 1.016 1.016)
					(thickness 0.1524)
				)
			)
		)
		(property "Device Type" "R402H16"
			(at 0.064008 -5.517896 180)
			(unlocked yes)
			(layer "F.Fab")
			(hide yes)
			(effects
				(font
					(size 1.016 1.016)
					(thickness 0.1524)
				)
			)
		)
		(duplicate_pad_numbers_are_jumpers no)
		(fp_rect
			(start -0.381 0.8382)
			(end 0.381 -0.8382)
			(stroke
				(width 0)
				(type default)
			)
			(fill no)
			(layer "F.CrtYd")
		)
		(fp_rect
			(start -0.381 0.8382)
			(end 0.381 -0.8382)
			(stroke
				(width 0)
				(type default)
			)
			(fill no)
			(layer "F.Fab")
		)
		(pad "1" smd custom
			(at 0 -0.4318 180)
			(size 0.127 0.127)
			(layers "F.Cu" "F.Mask" "F.Paste")
			(net "SMB_M_A1_R_DATA")
			(options
				(clearance outline)
				(anchor circle)
			)
			(primitives
				(gr_poly
					(pts
						(arc
							(start -0.2032 -0.2794)
							(mid -0.239121 -0.264521)
							(end -0.254 -0.2286)
						)
						(arc
							(start -0.254 0.2286)
							(mid -0.239121 0.264521)
							(end -0.2032 0.2794)
						)
						(arc
							(start 0.2032 0.2794)
							(mid 0.239121 0.264521)
							(end 0.254 0.2286)
						)
						(arc
							(start 0.254 -0.2286)
							(mid 0.239121 -0.264521)
							(end 0.2032 -0.2794)
						)
					)
					(width 0)
					(fill yes)
				)
			)
		)
		(pad "2" smd custom
			(at 0 0.4318 180)
			(size 0.127 0.127)
			(layers "F.Cu" "F.Mask" "F.Paste")
			(net "SMB_HOST_LV_DATA")
			(options
				(clearance outline)
				(anchor circle)
			)
			(primitives
				(gr_poly
					(pts
						(arc
							(start -0.2032 -0.2794)
							(mid -0.239121 -0.264521)
							(end -0.254 -0.2286)
						)
						(arc
							(start -0.254 0.2286)
							(mid -0.239121 0.264521)
							(end -0.2032 0.2794)
						)
						(arc
							(start 0.2032 0.2794)
							(mid 0.239121 0.264521)
							(end 0.254 0.2286)
						)
						(arc
							(start 0.254 -0.2286)
							(mid 0.239121 -0.264521)
							(end 0.2032 -0.2794)
						)
					)
					(width 0)
					(fill yes)
				)
			)
		)
	)
)
